#ISCELL
  mstr_misc dns *
  *
#ISCELL
  mstr_symbols bom_note *
  *
#ISCELL
  mstr_symbols cad_note *
  *
#ISCELL
  mstr_symbols design_note *
  *
#ISCELL
  mstr_symbols intel_corp_bpage *
  *
#CELL
  mstr_analog nc7sb3157 *
  page113_i107
#ISCELL
  mstr_symbols gnd *
  page113_i109
#ISCELL
  mstr_symbols gnd *
  page113_i110
#ISCELL
  mstr_standard offpage *
  page113_i111
#ISCELL
  mstr_standard offpage *
  page113_i112
#ISCELL
  mstr_standard offpage *
  page113_i113
#CELL
  dev_discrete cap_a *
  page113_i116
#CELL
  dev_discrete cap_a *
  page113_i117
#ISCELL
  mstr_symbols gnd *
  page113_i118
#CELL
  dev_discrete cap_a *
  page113_i119
#ISCELL
  mstr_symbols gnd *
  page113_i121
#ISCELL
  mstr_standard offpage *
  page113_i124
#ISCELL
  mstr_standard offpage *
  page113_i126
#CELL
  mstr_ttl 74cbtlv1g125 *
  page113_i127
#ISCELL
  mstr_standard offpage *
  page113_i128
#CELL
  mstr_discrete res *
  page113_i134
#ISCELL
  mstr_standard offpage *
  page113_i143
#ISCELL
  mstr_symbols gnd *
  page113_i146
#CELL
  dev_discrete cap_a *
  page113_i147
#ISCELL
  mstr_standard offpage *
  page113_i153
#ISCELL
  mstr_standard offpage *
  page113_i154
#ISCELL
  mstr_standard offpage *
  page113_i155
#ISCELL
  mstr_symbols p3v3_stby *
  page113_i160
#ISCELL
  mstr_symbols p3v3_stby *
  page113_i161
#ISCELL
  mstr_standard offpage *
  page113_i162
#ISCELL
  mstr_standard offpage *
  page113_i163
#CELL
  mstr_discrete res *
  page113_i168
#ISCELL
  mstr_standard offpage *
  page113_i169
#ISCELL
  mstr_symbols vcc_core *
  page113_i171
#ISCELL
  mstr_standard offpage *
  page113_i172
#CELL
  mstr_sconn sconn10_c12536004 *
  page113_i175
#ISCELL
  mstr_standard offpage *
  page113_i176
#CELL
  mstr_discrete res *
  page113_i179
#CELL
  mstr_discrete res *
  page113_i180
#ISCELL
  mstr_symbols gnd *
  page113_i182
#CELL
  mstr_ttl 74cbtlv1g125 *
  page113_i185
#ISCELL
  mstr_symbols gnd *
  page113_i186
#CELL
  mstr_discrete res *
  page113_i188
#CELL
  mstr_ttl 74cbtlv1g125 *
  page113_i190
#ISCELL
  mstr_standard offpage *
  page113_i192
#ISCELL
  mstr_standard offpage *
  page113_i193
#CELL
  mstr_discrete res *
  page113_i195
#CELL
  mstr_ttl 74cbtlv1g125 *
  page113_i196
#ISCELL
  mstr_standard offpage *
  page113_i197
#CELL
  mstr_discrete res *
  page113_i199
#ISCELL
  mstr_symbols gnd *
  page113_i200
#ISCELL
  mstr_symbols vcc_core *
  page113_i201
#CELL
  mstr_discrete res *
  page113_i202
#CELL
  mstr_discrete res *
  page113_i203
#CELL
  mstr_discrete res *
  page113_i204
#CELL
  mstr_discrete res *
  page113_i205
#CELL
  mstr_ttl 74cbtlv1g125 *
  page113_i206
#ISCELL
  mstr_standard offpage *
  page113_i212
#ISCELL
  mstr_standard offpage *
  page113_i213
#ISCELL
  mstr_standard offpage *
  page113_i214
#ISCELL
  mstr_standard offpage *
  page113_i215
#ISCELL
  mstr_symbols vcc_core *
  page113_i236
#ISCELL
  mstr_standard offpage *
  page113_i238
#CELL
  mstr_discrete res *
  page113_i239
#CELL
  mstr_discrete res *
  page113_i240
#ISCELL
  mstr_symbols vcc_core *
  page113_i241
#ISCELL
  mstr_standard offpage *
  page113_i242
#ISCELL
  mstr_standard offpage *
  page113_i243
#ISCELL
  mstr_standard offpage *
  page113_i244
#ISCELL
  mstr_symbols vcc_core *
  page113_i245
#CELL
  dev_discrete cap_a *
  page113_i246
#ISCELL
  mstr_symbols gnd *
  page113_i247
#CELL
  dev_discrete cap_a *
  page113_i248
#ISCELL
  mstr_symbols gnd *
  page113_i249
#CELL
  dev_discrete cap_a *
  page113_i250
#ISCELL
  mstr_symbols gnd *
  page113_i251
#CELL
  mstr_analog nc7sb3157 *
  page113_i255
#ISCELL
  mstr_standard offpage *
  page113_i256
#ISCELL
  mstr_standard offpage *
  page113_i257
#ISCELL
  mstr_standard offpage *
  page113_i258
#ISCELL
  mstr_symbols p3v3_stby *
  page113_i259
#ISCELL
  mstr_symbols gnd *
  page113_i261
#ISCELL
  mstr_symbols gnd *
  page113_i263
#ISCELL
  mstr_standard offpage *
  page113_i264
#CELL
  dev_discrete cap_a *
  page113_i265
#CELL
  dev_discrete cap_a *
  page113_i266
#CELL
  dev_discrete cap_a *
  page113_i267
#ISCELL
  mstr_symbols gnd *
  page113_i268
#ISCELL
  mstr_symbols p3v3_stby *
  page113_i269
